(kicad_pcb
	(version 20260206)
	(generator "pcbnew")
	(generator_version "10.0")
	(general
		(thickness 1.6)
		(legacy_teardrops no)
	)
	(paper "A4")
	(title_block
		(title "timecard-production-celestica-r4006 — R4006-B0001-02_R01.brd")
		(comment 1 "Time Appliance Project (Time Card) / footprints 677-681 of 1113")
	)
	(layers
		(0 "F.Cu" signal "TOP")
		(4 "In1.Cu" signal "L02_GND1")
		(6 "In2.Cu" signal "L03_SIG1")
		(8 "In3.Cu" signal "L04_GND2")
		(10 "In4.Cu" signal "L05_VCC1")
		(12 "In5.Cu" signal "L06_VCC2")
		(14 "In6.Cu" signal "L07_GND3")
		(16 "In7.Cu" signal "L08_SIG2")
		(18 "In8.Cu" signal "L09_GND4")
		(2 "B.Cu" signal "BOTTOM")
		(9 "F.Adhes" user "F.Adhesive")
		(11 "B.Adhes" user "B.Adhesive")
		(13 "F.Paste" user "Package Geometry/Pastemask Top")
		(15 "B.Paste" user "Package Geometry/Pastemask Bottom")
		(5 "F.SilkS" user "Ref Des/Silkscreen Top")
		(7 "B.SilkS" user "Ref Des/Silkscreen Bottom")
		(1 "F.Mask" user "Board Geometry/Soldermask Top")
		(3 "B.Mask" user "Board Geometry/Soldermask Bottom")
		(17 "Dwgs.User" user "User.Drawings")
		(19 "Cmts.User" user "User.Comments")
		(21 "Eco1.User" user "User.Eco1")
		(23 "Eco2.User" user "User.Eco2")
		(25 "Edge.Cuts" user "Board Geometry/Outline")
		(27 "Margin" user)
		(31 "F.CrtYd" user "Package Geometry/Place Bound Top")
		(29 "B.CrtYd" user "Package Geometry/Place Bound Bottom")
		(35 "F.Fab" user "Ref Des/Assembly Top")
		(33 "B.Fab" user "Ref Des/Assembly Bottom")
	)
	(footprint ""
		(layer "B.Cu")
		(at 99.846892 -44.323254 -90)
		(property "Reference" "C205"
			(at -0.634746 -0.959358 270)
			(unlocked yes)
			(layer "B.SilkS")
			(effects
				(font
					(size 0.635 0.4064)
					(thickness 0.1524)
				)
				(justify mirror)
			)
		)
		(property "Value" "VAL*"
			(at 0 3.718306 270)
			(unlocked yes)
			(layer "B.Fab")
			(hide yes)
			(effects
				(font
					(size 0.7874 0.5842)
					(thickness 0.127)
				)
				(justify mirror)
			)
		)
		(property "Tolerance" "TOL*"
			(at 0 4.861306 270)
			(unlocked yes)
			(layer "Cmts.User")
			(hide yes)
			(effects
				(font
					(size 0.7874 0.5842)
					(thickness 0.127)
				)
				(justify mirror)
			)
		)
		(property "User Part Number" "PARTNUM*"
			(at 0 2.575306 270)
			(unlocked yes)
			(layer "Cmts.User")
			(hide yes)
			(effects
				(font
					(size 0.7874 0.5842)
					(thickness 0.127)
				)
				(justify mirror)
			)
		)
		(property "Device Type" "CAPACITOR-G105-0B104-CK,0.1UF,A"
			(at 0 1.432306 270)
			(unlocked yes)
			(layer "B.Fab")
			(hide yes)
			(effects
				(font
					(size 0.7874 0.5842)
					(thickness 0.127)
				)
				(justify mirror)
			)
		)
		(duplicate_pad_numbers_are_jumpers no)
		(fp_line
			(start -0.970026 0.4699)
			(end 0.970026 0.4699)
			(stroke
				(width 0.1)
				(type default)
			)
			(layer "B.SilkS")
		)
		(fp_line
			(start 0.970026 0.4699)
			(end 0.970026 -0.4699)
			(stroke
				(width 0.1)
				(type default)
			)
			(layer "B.SilkS")
		)
		(fp_line
			(start -0.970026 -0.4699)
			(end -0.970026 0.4699)
			(stroke
				(width 0.1)
				(type default)
			)
			(layer "B.SilkS")
		)
		(fp_line
			(start 0.970026 -0.4699)
			(end -0.970026 -0.4699)
			(stroke
				(width 0.1)
				(type default)
			)
			(layer "B.SilkS")
		)
		(fp_poly
			(pts
				(xy 0.970026 0.4699) (xy -0.970026 0.4699) (xy -0.970026 -0.4699) (xy 0.970026 -0.4699)
			)
			(stroke
				(width 0)
				(type default)
			)
			(fill no)
			(layer "B.CrtYd")
		)
		(fp_line
			(start -0.508 0.3048)
			(end 0.508 0.3048)
			(stroke
				(width 0.1)
				(type default)
			)
			(layer "B.Fab")
		)
		(fp_line
			(start 0.508 0.3048)
			(end 0.508 -0.3048)
			(stroke
				(width 0.1)
				(type default)
			)
			(layer "B.Fab")
		)
		(fp_line
			(start -0.508 -0.3048)
			(end -0.508 0.3048)
			(stroke
				(width 0.1)
				(type default)
			)
			(layer "B.Fab")
		)
		(fp_line
			(start 0.508 -0.3048)
			(end -0.508 -0.3048)
			(stroke
				(width 0.1)
				(type default)
			)
			(layer "B.Fab")
		)
		(pad "1" smd circle
			(at 0.500126 0 90)
			(size 0.635 0.635)
			(layers "B.Cu" "B.Mask" "B.Paste")
			(net "FPGA_MGTAVTT")
		)
		(pad "2" smd circle
			(at -0.500126 0 90)
			(size 0.635 0.635)
			(layers "B.Cu" "B.Mask" "B.Paste")
			(net "SG")
		)
	)
	(footprint ""
		(layer "B.Cu")
		(at 137.795 -17.526 180)
		(property "Reference" "R233"
			(at 1.27 1.10363 0)
			(unlocked yes)
			(layer "B.SilkS")
			(effects
				(font
					(size 0.7874 0.5842)
					(thickness 0.1524)
				)
				(justify mirror)
			)
		)
		(property "Value" "VAL*"
			(at -0.0508 2.245106 180)
			(unlocked yes)
			(layer "B.Fab")
			(hide yes)
			(effects
				(font
					(size 0.7874 0.5842)
					(thickness 0.1524)
				)
				(justify mirror)
			)
		)
		(property "Tolerance" "TOL*"
			(at -0.0508 3.261106 180)
			(unlocked yes)
			(layer "Cmts.User")
			(hide yes)
			(effects
				(font
					(size 0.7874 0.5842)
					(thickness 0.1524)
				)
				(justify mirror)
			)
		)
		(property "Device Type" "RESISTOR-G155-02101-01,2.1KOHMA"
			(at -0.0762 1.254506 180)
			(unlocked yes)
			(layer "B.Fab")
			(hide yes)
			(effects
				(font
					(size 0.7874 0.5842)
					(thickness 0.1524)
				)
				(justify mirror)
			)
		)
		(property "User Part Number" "PARTNUM*"
			(at -0.0762 4.302506 180)
			(unlocked yes)
			(layer "Cmts.User")
			(hide yes)
			(effects
				(font
					(size 0.7874 0.5842)
					(thickness 0.1524)
				)
				(justify mirror)
			)
		)
		(duplicate_pad_numbers_are_jumpers no)
		(fp_line
			(start 1.143 0.5588)
			(end -1.143 0.5588)
			(stroke
				(width 0.1)
				(type default)
			)
			(layer "B.SilkS")
		)
		(fp_line
			(start 1.143 -0.5588)
			(end 1.143 0.5588)
			(stroke
				(width 0.1)
				(type default)
			)
			(layer "B.SilkS")
		)
		(fp_line
			(start -1.143 0.5588)
			(end -1.143 -0.5588)
			(stroke
				(width 0.1)
				(type default)
			)
			(layer "B.SilkS")
		)
		(fp_line
			(start -1.143 -0.5588)
			(end 1.143 -0.5588)
			(stroke
				(width 0.1)
				(type default)
			)
			(layer "B.SilkS")
		)
		(fp_rect
			(start 1.143 -0.5588)
			(end -1.143 0.5588)
			(stroke
				(width 0)
				(type default)
			)
			(fill no)
			(layer "B.CrtYd")
		)
		(fp_line
			(start 0.508 0.3048)
			(end -0.508 0.3048)
			(stroke
				(width 0.1)
				(type default)
			)
			(layer "B.Fab")
		)
		(fp_line
			(start 0.508 -0.3048)
			(end 0.508 0.3048)
			(stroke
				(width 0.1)
				(type default)
			)
			(layer "B.Fab")
		)
		(fp_line
			(start -0.508 0.3048)
			(end -0.508 -0.3048)
			(stroke
				(width 0.1)
				(type default)
			)
			(layer "B.Fab")
		)
		(fp_line
			(start -0.508 -0.3048)
			(end 0.508 -0.3048)
			(stroke
				(width 0.1)
				(type default)
			)
			(layer "B.Fab")
		)
		(pad "1" smd rect
			(at 0.5334 0)
			(size 0.7112 0.6096)
			(layers "B.Cu" "B.Mask" "B.Paste")
			(net "SG")
		)
		(pad "2" smd rect
			(at -0.5334 0)
			(size 0.7112 0.6096)
			(layers "B.Cu" "B.Mask" "B.Paste")
			(net "UNNAMED_515_ISL80101IRAJZDFN10_")
		)
		(zone
			(layer "B.Cu")
			(hatch none 0.5)
			(connect_pads
				(clearance 0)
			)
			(min_thickness 0.25)
			(keepout
				(tracks allowed)
				(vias not_allowed)
				(pads allowed)
				(copperpour not_allowed)
				(footprints allowed)
			)
			(placement
				(enabled no)
				(sheetname "")
			)
			(fill
				(thermal_gap 0.5)
				(thermal_bridge_width 0.5)
				(island_removal_mode 0)
			)
			(polygon
				(pts
					(xy 137.7188 -17.2212) (xy 137.8712 -17.2212) (xy 137.8712 -17.8308) (xy 137.7188 -17.8308)
				)
			)
		)
	)
	(footprint ""
		(layer "B.Cu")
		(at 17.653 -37.973 180)
		(property "Reference" "R59"
			(at 0 -2.32537 0)
			(unlocked yes)
			(layer "B.SilkS")
			(effects
				(font
					(size 0.7874 0.5842)
					(thickness 0.1524)
				)
				(justify mirror)
			)
		)
		(property "Value" "VAL*"
			(at -0.02032 2.13233 180)
			(unlocked yes)
			(layer "B.Fab")
			(hide yes)
			(effects
				(font
					(size 0.7874 0.5842)
					(thickness 0.1524)
				)
				(justify mirror)
			)
		)
		(property "Device Type" "RESISTOR-G155-133R0-01,33OHM,1%"
			(at -0.008382 1.210564 180)
			(unlocked yes)
			(layer "B.Fab")
			(hide yes)
			(effects
				(font
					(size 0.7874 0.5842)
					(thickness 0.1524)
				)
				(justify mirror)
			)
		)
		(property "User Part Number" "PARTNUM*"
			(at -0.02032 4.024884 180)
			(unlocked yes)
			(layer "Cmts.User")
			(hide yes)
			(effects
				(font
					(size 0.7874 0.5842)
					(thickness 0.1524)
				)
				(justify mirror)
			)
		)
		(property "Tolerance" "TOL*"
			(at -0.044704 3.05435 180)
			(unlocked yes)
			(layer "Cmts.User")
			(hide yes)
			(effects
				(font
					(size 0.7874 0.5842)
					(thickness 0.1524)
				)
				(justify mirror)
			)
		)
		(duplicate_pad_numbers_are_jumpers no)
		(fp_line
			(start 1.143 0.5588)
			(end -1.143 0.5588)
			(stroke
				(width 0.1)
				(type default)
			)
			(layer "B.SilkS")
		)
		(fp_line
			(start 1.143 -0.5588)
			(end 1.143 0.5588)
			(stroke
				(width 0.1)
				(type default)
			)
			(layer "B.SilkS")
		)
		(fp_line
			(start -1.143 0.5588)
			(end -1.143 -0.5588)
			(stroke
				(width 0.1)
				(type default)
			)
			(layer "B.SilkS")
		)
		(fp_line
			(start -1.143 -0.5588)
			(end 1.143 -0.5588)
			(stroke
				(width 0.1)
				(type default)
			)
			(layer "B.SilkS")
		)
		(fp_rect
			(start 1.143 0.5588)
			(end -1.143 -0.5588)
			(stroke
				(width 0)
				(type default)
			)
			(fill no)
			(layer "B.CrtYd")
		)
		(fp_line
			(start 0.508 0.3048)
			(end -0.508 0.3048)
			(stroke
				(width 0.1)
				(type default)
			)
			(layer "B.Fab")
		)
		(fp_line
			(start 0.508 -0.3048)
			(end 0.508 0.3048)
			(stroke
				(width 0.1)
				(type default)
			)
			(layer "B.Fab")
		)
		(fp_line
			(start -0.508 0.3048)
			(end -0.508 -0.3048)
			(stroke
				(width 0.1)
				(type default)
			)
			(layer "B.Fab")
		)
		(fp_line
			(start -0.508 -0.3048)
			(end 0.508 -0.3048)
			(stroke
				(width 0.1)
				(type default)
			)
			(layer "B.Fab")
		)
		(pad "1" smd rect
			(at 0.5334 0)
			(size 0.7112 0.6096)
			(layers "B.Cu" "B.Mask" "B.Paste")
			(net "UNNAMED_5_CONNHDR2X2MSSMT_I12_1")
		)
		(pad "2" smd rect
			(at -0.5334 0)
			(size 0.7112 0.6096)
			(layers "B.Cu" "B.Mask" "B.Paste")
			(net "R_PCA9546_I2C_SCL")
		)
		(zone
			(layer "B.Cu")
			(hatch none 0.5)
			(connect_pads
				(clearance 0)
			)
			(min_thickness 0.25)
			(keepout
				(tracks allowed)
				(vias not_allowed)
				(pads allowed)
				(copperpour not_allowed)
				(footprints allowed)
			)
			(placement
				(enabled no)
				(sheetname "")
			)
			(fill
				(thermal_gap 0.5)
				(thermal_bridge_width 0.5)
				(island_removal_mode 0)
			)
			(polygon
				(pts
					(xy 17.5768 -38.2778) (xy 17.5768 -37.6682) (xy 17.7292 -37.6682) (xy 17.7292 -38.2778)
				)
			)
		)
	)
	(footprint ""
		(layer "B.Cu")
		(at 77.3938 -81.534 180)
		(property "Reference" "R61"
			(at 2.9718 -0.03937 0)
			(unlocked yes)
			(layer "B.SilkS")
			(effects
				(font
					(size 0.7874 0.5842)
					(thickness 0.1524)
				)
				(justify mirror)
			)
		)
		(property "Value" "VAL*"
			(at -0.02032 2.13233 180)
			(unlocked yes)
			(layer "B.Fab")
			(hide yes)
			(effects
				(font
					(size 0.7874 0.5842)
					(thickness 0.1524)
				)
				(justify mirror)
			)
		)
		(property "Tolerance" "TOL*"
			(at -0.044704 3.05435 180)
			(unlocked yes)
			(layer "Cmts.User")
			(hide yes)
			(effects
				(font
					(size 0.7874 0.5842)
					(thickness 0.1524)
				)
				(justify mirror)
			)
		)
		(property "User Part Number" "PARTNUM*"
			(at -0.02032 4.024884 180)
			(unlocked yes)
			(layer "Cmts.User")
			(hide yes)
			(effects
				(font
					(size 0.7874 0.5842)
					(thickness 0.1524)
				)
				(justify mirror)
			)
		)
		(property "Device Type" "RESISTOR-G155-100R0-J0,0OHM,-"
			(at -0.008382 1.210564 180)
			(unlocked yes)
			(layer "B.Fab")
			(hide yes)
			(effects
				(font
					(size 0.7874 0.5842)
					(thickness 0.1524)
				)
				(justify mirror)
			)
		)
		(duplicate_pad_numbers_are_jumpers no)
		(fp_line
			(start 1.143 0.5588)
			(end -1.143 0.5588)
			(stroke
				(width 0.1)
				(type default)
			)
			(layer "B.SilkS")
		)
		(fp_line
			(start 1.143 -0.5588)
			(end 1.143 0.5588)
			(stroke
				(width 0.1)
				(type default)
			)
			(layer "B.SilkS")
		)
		(fp_line
			(start -1.143 0.5588)
			(end -1.143 -0.5588)
			(stroke
				(width 0.1)
				(type default)
			)
			(layer "B.SilkS")
		)
		(fp_line
			(start -1.143 -0.5588)
			(end 1.143 -0.5588)
			(stroke
				(width 0.1)
				(type default)
			)
			(layer "B.SilkS")
		)
		(fp_poly
			(pts
				(xy 1.143 0.5588) (xy -1.143 0.5588) (xy -1.143 -0.5588) (xy 1.143 -0.5588)
			)
			(stroke
				(width 0)
				(type default)
			)
			(fill no)
			(layer "B.CrtYd")
		)
		(fp_line
			(start 0.508 0.3048)
			(end -0.508 0.3048)
			(stroke
				(width 0.1)
				(type default)
			)
			(layer "B.Fab")
		)
		(fp_line
			(start 0.508 -0.3048)
			(end 0.508 0.3048)
			(stroke
				(width 0.1)
				(type default)
			)
			(layer "B.Fab")
		)
		(fp_line
			(start -0.508 0.3048)
			(end -0.508 -0.3048)
			(stroke
				(width 0.1)
				(type default)
			)
			(layer "B.Fab")
		)
		(fp_line
			(start -0.508 -0.3048)
			(end 0.508 -0.3048)
			(stroke
				(width 0.1)
				(type default)
			)
			(layer "B.Fab")
		)
		(pad "1" smd rect
			(at 0.5334 0)
			(size 0.7112 0.6096)
			(layers "B.Cu" "B.Mask" "B.Paste")
			(net "VDD_PCA9546A")
		)
		(pad "2" smd rect
			(at -0.5334 0)
			(size 0.7112 0.6096)
			(layers "B.Cu" "B.Mask" "B.Paste")
			(net "XP2R5V_FPGA")
		)
		(zone
			(layer "B.Cu")
			(hatch none 0.5)
			(connect_pads
				(clearance 0)
			)
			(min_thickness 0.25)
			(keepout
				(tracks not_allowed)
				(vias allowed)
				(pads allowed)
				(copperpour not_allowed)
				(footprints allowed)
			)
			(placement
				(enabled no)
				(sheetname "")
			)
			(fill
				(thermal_gap 0.5)
				(thermal_bridge_width 0.5)
				(island_removal_mode 0)
			)
			(polygon
				(pts
					(xy 77.3176 -81.8388) (xy 77.3176 -81.2292) (xy 77.47 -81.2292) (xy 77.47 -81.8388)
				)
			)
		)
		(zone
			(layer "B.Cu")
			(hatch none 0.5)
			(connect_pads
				(clearance 0)
			)
			(min_thickness 0.25)
			(keepout
				(tracks allowed)
				(vias not_allowed)
				(pads allowed)
				(copperpour not_allowed)
				(footprints allowed)
			)
			(placement
				(enabled no)
				(sheetname "")
			)
			(fill
				(thermal_gap 0.5)
				(thermal_bridge_width 0.5)
				(island_removal_mode 0)
			)
			(polygon
				(pts
					(xy 77.3176 -81.8388) (xy 77.3176 -81.2292) (xy 77.47 -81.2292) (xy 77.47 -81.8388)
				)
			)
		)
	)
	(footprint ""
		(layer "B.Cu")
		(at 22.0472 -18.034 180)
		(property "Reference" "R24"
			(at -2.3368 -0.03937 0)
			(unlocked yes)
			(layer "B.SilkS")
			(effects
				(font
					(size 0.7874 0.5842)
					(thickness 0.1524)
				)
				(justify mirror)
			)
		)
		(property "Value" "VAL*"
			(at -0.02032 2.13233 180)
			(unlocked yes)
			(layer "B.Fab")
			(hide yes)
			(effects
				(font
					(size 0.7874 0.5842)
					(thickness 0.1524)
				)
				(justify mirror)
			)
		)
		(property "Device Type" "RESISTOR-G155-14701-01,4.7KOHMA"
			(at -0.008382 1.210564 180)
			(unlocked yes)
			(layer "B.Fab")
			(hide yes)
			(effects
				(font
					(size 0.7874 0.5842)
					(thickness 0.1524)
				)
				(justify mirror)
			)
		)
		(property "User Part Number" "PARTNUM*"
			(at -0.02032 4.024884 180)
			(unlocked yes)
			(layer "Cmts.User")
			(hide yes)
			(effects
				(font
					(size 0.7874 0.5842)
					(thickness 0.1524)
				)
				(justify mirror)
			)
		)
		(property "Tolerance" "TOL*"
			(at -0.044704 3.05435 180)
			(unlocked yes)
			(layer "Cmts.User")
			(hide yes)
			(effects
				(font
					(size 0.7874 0.5842)
					(thickness 0.1524)
				)
				(justify mirror)
			)
		)
		(duplicate_pad_numbers_are_jumpers no)
		(fp_line
			(start 1.143 0.5588)
			(end -1.143 0.5588)
			(stroke
				(width 0.1)
				(type default)
			)
			(layer "B.SilkS")
		)
		(fp_line
			(start 1.143 -0.5588)
			(end 1.143 0.5588)
			(stroke
				(width 0.1)
				(type default)
			)
			(layer "B.SilkS")
		)
		(fp_line
			(start -1.143 0.5588)
			(end -1.143 -0.5588)
			(stroke
				(width 0.1)
				(type default)
			)
			(layer "B.SilkS")
		)
		(fp_line
			(start -1.143 -0.5588)
			(end 1.143 -0.5588)
			(stroke
				(width 0.1)
				(type default)
			)
			(layer "B.SilkS")
		)
		(fp_rect
			(start -1.143 0.5588)
			(end 1.143 -0.5588)
			(stroke
				(width 0)
				(type default)
			)
			(fill no)
			(layer "B.CrtYd")
		)
		(fp_line
			(start 0.508 0.3048)
			(end -0.508 0.3048)
			(stroke
				(width 0.1)
				(type default)
			)
			(layer "B.Fab")
		)
		(fp_line
			(start 0.508 -0.3048)
			(end 0.508 0.3048)
			(stroke
				(width 0.1)
				(type default)
			)
			(layer "B.Fab")
		)
		(fp_line
			(start -0.508 0.3048)
			(end -0.508 -0.3048)
			(stroke
				(width 0.1)
				(type default)
			)
			(layer "B.Fab")
		)
		(fp_line
			(start -0.508 -0.3048)
			(end 0.508 -0.3048)
			(stroke
				(width 0.1)
				(type default)
			)
			(layer "B.Fab")
		)
		(pad "1" smd rect
			(at 0.5334 0)
			(size 0.7112 0.6096)
			(layers "B.Cu" "B.Mask" "B.Paste")
			(net "SEC_EEPROM_WP")
		)
		(pad "2" smd rect
			(at -0.5334 0)
			(size 0.7112 0.6096)
			(layers "B.Cu" "B.Mask" "B.Paste")
			(net "SG")
		)
		(zone
			(layer "B.Cu")
			(hatch none 0.5)
			(connect_pads
				(clearance 0)
			)
			(min_thickness 0.25)
			(keepout
				(tracks allowed)
				(vias not_allowed)
				(pads allowed)
				(copperpour not_allowed)
				(footprints allowed)
			)
			(placement
				(enabled no)
				(sheetname "")
			)
			(fill
				(thermal_gap 0.5)
				(thermal_bridge_width 0.5)
				(island_removal_mode 0)
			)
			(polygon
				(pts
					(xy 22.1234 -18.3388) (xy 21.971 -18.3388) (xy 21.971 -17.7292) (xy 22.1234 -17.7292)
				)
			)
		)
	)
)
